FILE_TYPE = CONNECTIVITY;
{Allegro Design Entry HDL 17.2-2016 S081 (4005846) 1/11/2022}
"PAGE_NUMBER" = 17;
0"NC";
1"NC_CPU0_HBM2_VIEWDIG0";
2"NC_CPU0_HBM2_VIEWDIG1";
3"NC_CPU0_MDFI_DIE11_NS0";
4"NC_CPU0_MDFI_DIE11_EW0";
5"NC_CPU0_MDFI_DIE11_NS1";
6"NC_CPU0_VIEWPIN_GNR2";
7"NC_CPU0_VIEWPIN_GNR0";
8"NC_CPU0_HBM1_VIEWDIG1";
9"NC_CPU0_VIEWPIN_GNR1";
10"NC_CPU0_VIEWPIN_GNR3";
11"NC_CPU0_HBM0_VIEWDIG1";
12"NC_CPU0_HBM0_VIEWDIG0";
13"NC_CPU0_HBM1_VIEWDIG0";
14"NC_CPU0_MDFI_DIE01_EW0";
15"NC_CPU0_SOC_SPARE0";
16"NC_CPU0_SOC_SPARE4";
17"NC_CPU0_MDFI_DIE01_NS1";
18"TP_CPU0_DIE_HVM_EN_LVC1";
19"NC_CPU0_MDFI_DIE01_NS0";
20"NC_CPU0_HBM3_VIEWDIG0";
21"NC_CPU0_MDFI_DIE00_NS1";
22"NC_CPU0_MDFI_DIE00_NS0";
23"NC_CPU0_HBM3_VIEWDIG1";
24"NC_CPU0_SOC_SPARE1";
25"NC_CPU0_MDFI_DIE00_EW0";
26"NC_CPU0_SOC_SPARE5";
27"NC_CPU0_MDFI_DIE00_EW1";
28"NC_CPU0_MDFI_DIE01_EW1";
29"NC_CPU0_MDFI_DIE10_NS1";
30"NC_CPU0_MDFI_DIE10_EW0";
31"NC_CPU0_MDFI_DIE10_EW1";
32"NC_CPU0_MDFI_DIE10_NS0";
33"NC_CPU0_MDFI_DIE11_EW1";
%"SOCKET4677_AZIF0045P001C01CS"
"5","(475,2925)","0","pure_quanta","I1";
;
PART_NUMBER"DGA^7000023"
PART_TYPE"SMLF"
MATERIAL"IO"
VALUE"SOCKET4677_AZIF0045-P001C01CS"
$LOCATION"U2"
CDS_LIB"pure_quanta"
NEEDS_NO_SIZE"TRUE"
CDS_LMAN_SYM_OUTLINE"-1050,1050,1050,-1000"
CDS_LOCATION"U2"
$SEC"5"
CDS_SEC"5";
"RSVD99"
$PN"CH69"33;
"RSVD92"
$PN"CF22"32;
"RSVD85"
$PN"CD30"31;
"RSVD84"
$PN"CD26"30;
"RSVD83"
$PN"CD22"29;
"RSVD82"
$PN"CC66"28;
"RSVD71"
$PN"BR21"27;
"RSVD68"
$PN"BP65"26;
"RSVD67"
$PN"BP22"25;
"RSVD65"
$PN"BM65"24;
"RSVD63"
$PN"BL60"23;
"RSVD60"
$PN"BK22"22;
"RSVD57"
$PN"BJ21"21;
"RSVD54"
$PN"BG78"20;
"RSVD51"
$PN"BF71"19;
"RSVD45"
$PN"BE21"18;
"RSVD43"
$PN"BD71"17;
"RSVD31"
$PN"BA25"16;
"RSVD26"
$PN"AY24"15;
"RSVD21"
$PN"AV65"14;
"RSVD165"
$PN"W17"13;
"RSVD164"
$PN"U17"12;
"RSVD160"
$PN"EG17"11;
"RSVD154"
$PN"CY57"10;
"RSVD149"
$PN"CW58"9;
"RSVD147"
$PN"CW41"8;
"RSVD138"
$PN"CT26"7;
"RSVD133"
$PN"CR25"6;
"RSVD112"
$PN"CK67"5;
"RSVD107"
$PN"CJ70"4;
"RSVD106"
$PN"CJ68"3;
"RSVD1"
$PN"AD77"2;
"RSVD0"
$PN"AC78"1;
END.
